# SCM (Grand Teton) — schematic netlist excerpt (pin names and nets, part order shuffled) for the footprints in the layout excerpt that follows; sources: Cadence DE-HDL packaged netlist, KiCad conversion of 12092022_DA0F0TMDCD0_F0T_Management_Board_D_brd_V3_OCP.brd

R413  Q_RES  100 1% CHIP  pkg 0402LF  page 26 : A = FRU_E2 ; B = GND
R575  Q_RES  0 5% CHIP  pkg 0402LF  page 36 : A = FM_P12V_HSC_ENABLE ; B = FM_P12V_HSC_ENABLE_R2

(kicad_pcb
	(version 20260206)
	(generator "pcbnew")
	(generator_version "10.0")
	(general
		(thickness 1.6)
		(legacy_teardrops no)
	)
	(paper "A4")
	(title_block
		(title "12092022_DA0F0TMDCD0_F0T_Management_Board_D_brd_V3_OCP.brd")
		(comment 1 "Grand Teton / footprints 1025-1026 of 1440")
	)
	(layers
		(0 "F.Cu" signal "TOP")
		(4 "In1.Cu" signal "GND")
		(6 "In2.Cu" signal "IN1")
		(8 "In3.Cu" signal "GND1")
		(10 "In4.Cu" signal "IN2")
		(12 "In5.Cu" signal "VCC")
		(14 "In6.Cu" signal "VCC1")
		(16 "In7.Cu" signal "IN3")
		(18 "In8.Cu" signal "GND2")
		(20 "In9.Cu" signal "IN4")
		(22 "In10.Cu" signal "GND3")
		(2 "B.Cu" signal "BOTTOM")
		(9 "F.Adhes" user "F.Adhesive")
		(11 "B.Adhes" user "B.Adhesive")
		(13 "F.Paste" user "Package Geometry/Pastemask Top")
		(15 "B.Paste" user "Package Geometry/Pastemask Bottom")
		(5 "F.SilkS" user "Ref Des/Silkscreen Top")
		(7 "B.SilkS" user "Ref Des/Silkscreen Bottom")
		(1 "F.Mask" user "Board Geometry/Soldermask Top")
		(3 "B.Mask" user "Board Geometry/Soldermask Bottom")
		(17 "Dwgs.User" user "User.Drawings")
		(19 "Cmts.User" user "User.Comments")
		(21 "Eco1.User" user "User.Eco1")
		(23 "Eco2.User" user "User.Eco2")
		(25 "Edge.Cuts" user "Board Geometry/Outline")
		(27 "Margin" user)
		(31 "F.CrtYd" user "Package Geometry/Place Bound Top")
		(29 "B.CrtYd" user "Package Geometry/Place Bound Bottom")
		(35 "F.Fab" user "Ref Des/Assembly Top")
		(33 "B.Fab" user "Ref Des/Assembly Bottom")
	)
	(footprint ""
		(layer "B.Cu")
		(at 25.019 -101.981 90)
		(property "Reference" "R575"
			(at 0 0 90)
			(layer "B.SilkS")
			(hide yes)
			(effects
				(font
					(size 1.27 1.27)
				)
				(justify mirror)
			)
		)
		(property "Value" ""
			(at 0 0 90)
			(layer "B.Fab")
			(effects
				(font
					(size 1.27 1.27)
				)
				(justify mirror)
			)
		)
		(duplicate_pad_numbers_are_jumpers no)
		(fp_line
			(start 0.7874 -0.4064)
			(end -0.7874 -0.4064)
			(stroke
				(width 0.1524)
				(type default)
			)
			(layer "B.SilkS")
		)
		(fp_line
			(start -0.7874 -0.4064)
			(end -0.7874 0.4064)
			(stroke
				(width 0.1524)
				(type default)
			)
			(layer "B.SilkS")
		)
		(fp_line
			(start 0.7874 0.4064)
			(end 0.7874 -0.4064)
			(stroke
				(width 0.1524)
				(type default)
			)
			(layer "B.SilkS")
		)
		(fp_line
			(start -0.7874 0.4064)
			(end 0.7874 0.4064)
			(stroke
				(width 0.1524)
				(type default)
			)
			(layer "B.SilkS")
		)
		(fp_line
			(start 0.67945 -0.305054)
			(end 0.12065 -0.305054)
			(stroke
				(width 0.1)
				(type default)
			)
			(layer "B.Fab")
		)
		(fp_line
			(start 0.12065 -0.305054)
			(end 0.12065 -0.2794)
			(stroke
				(width 0.1)
				(type default)
			)
			(layer "B.Fab")
		)
		(fp_line
			(start -0.12065 -0.3048)
			(end -0.67945 -0.3048)
			(stroke
				(width 0.1)
				(type default)
			)
			(layer "B.Fab")
		)
		(fp_line
			(start -0.67945 -0.3048)
			(end -0.67945 0.3048)
			(stroke
				(width 0.1)
				(type default)
			)
			(layer "B.Fab")
		)
		(fp_line
			(start 0.12065 -0.2794)
			(end -0.12065 -0.2794)
			(stroke
				(width 0.1)
				(type default)
			)
			(layer "B.Fab")
		)
		(fp_line
			(start -0.12065 -0.2794)
			(end -0.12065 -0.3048)
			(stroke
				(width 0.1)
				(type default)
			)
			(layer "B.Fab")
		)
		(fp_line
			(start 0.12065 0.2794)
			(end 0.12065 0.3048)
			(stroke
				(width 0.1)
				(type default)
			)
			(layer "B.Fab")
		)
		(fp_line
			(start -0.120396 0.2794)
			(end 0.12065 0.2794)
			(stroke
				(width 0.1)
				(type default)
			)
			(layer "B.Fab")
		)
		(fp_line
			(start 0.67945 0.3048)
			(end 0.67945 -0.305054)
			(stroke
				(width 0.1)
				(type default)
			)
			(layer "B.Fab")
		)
		(fp_line
			(start 0.12065 0.3048)
			(end 0.67945 0.3048)
			(stroke
				(width 0.1)
				(type default)
			)
			(layer "B.Fab")
		)
		(fp_line
			(start -0.120396 0.3048)
			(end -0.120396 0.2794)
			(stroke
				(width 0.1)
				(type default)
			)
			(layer "B.Fab")
		)
		(fp_line
			(start -0.67945 0.3048)
			(end -0.120396 0.3048)
			(stroke
				(width 0.1)
				(type default)
			)
			(layer "B.Fab")
		)
		(pad "1" smd circle
			(at 0.40005 0 270)
			(size 0 0)
			(layers "B.Cu" "B.Mask" "B.Paste")
			(net "FM_P12V_HSC_ENABLE")
		)
		(pad "2" smd circle
			(at -0.40005 0 270)
			(size 0 0)
			(layers "B.Cu" "B.Mask" "B.Paste")
			(net "FM_P12V_HSC_ENABLE_R2")
		)
	)
	(footprint ""
		(layer "B.Cu")
		(at 83.283552 -26.587704 180)
		(property "Reference" "R413"
			(at 0 0 0)
			(layer "B.SilkS")
			(hide yes)
			(effects
				(font
					(size 1.27 1.27)
				)
				(justify mirror)
			)
		)
		(property "Value" ""
			(at 0 0 0)
			(layer "B.Fab")
			(effects
				(font
					(size 1.27 1.27)
				)
				(justify mirror)
			)
		)
		(duplicate_pad_numbers_are_jumpers no)
		(fp_line
			(start 0.7874 0.4064)
			(end 0.7874 -0.4064)
			(stroke
				(width 0.1524)
				(type default)
			)
			(layer "B.SilkS")
		)
		(fp_line
			(start 0.7874 -0.4064)
			(end -0.7874 -0.4064)
			(stroke
				(width 0.1524)
				(type default)
			)
			(layer "B.SilkS")
		)
		(fp_line
			(start -0.7874 0.4064)
			(end 0.7874 0.4064)
			(stroke
				(width 0.1524)
				(type default)
			)
			(layer "B.SilkS")
		)
		(fp_line
			(start -0.7874 -0.4064)
			(end -0.7874 0.4064)
			(stroke
				(width 0.1524)
				(type default)
			)
			(layer "B.SilkS")
		)
		(fp_line
			(start 0.67945 0.3048)
			(end 0.67945 -0.305054)
			(stroke
				(width 0.1)
				(type default)
			)
			(layer "B.Fab")
		)
		(fp_line
			(start 0.67945 -0.305054)
			(end 0.12065 -0.305054)
			(stroke
				(width 0.1)
				(type default)
			)
			(layer "B.Fab")
		)
		(fp_line
			(start 0.12065 0.3048)
			(end 0.67945 0.3048)
			(stroke
				(width 0.1)
				(type default)
			)
			(layer "B.Fab")
		)
		(fp_line
			(start 0.12065 0.2794)
			(end 0.12065 0.3048)
			(stroke
				(width 0.1)
				(type default)
			)
			(layer "B.Fab")
		)
		(fp_line
			(start 0.12065 -0.2794)
			(end -0.12065 -0.2794)
			(stroke
				(width 0.1)
				(type default)
			)
			(layer "B.Fab")
		)
		(fp_line
			(start 0.12065 -0.305054)
			(end 0.12065 -0.2794)
			(stroke
				(width 0.1)
				(type default)
			)
			(layer "B.Fab")
		)
		(fp_line
			(start -0.120396 0.3048)
			(end -0.120396 0.2794)
			(stroke
				(width 0.1)
				(type default)
			)
			(layer "B.Fab")
		)
		(fp_line
			(start -0.120396 0.2794)
			(end 0.12065 0.2794)
			(stroke
				(width 0.1)
				(type default)
			)
			(layer "B.Fab")
		)
		(fp_line
			(start -0.12065 -0.2794)
			(end -0.12065 -0.3048)
			(stroke
				(width 0.1)
				(type default)
			)
			(layer "B.Fab")
		)
		(fp_line
			(start -0.12065 -0.3048)
			(end -0.67945 -0.3048)
			(stroke
				(width 0.1)
				(type default)
			)
			(layer "B.Fab")
		)
		(fp_line
			(start -0.67945 0.3048)
			(end -0.120396 0.3048)
			(stroke
				(width 0.1)
				(type default)
			)
			(layer "B.Fab")
		)
		(fp_line
			(start -0.67945 -0.3048)
			(end -0.67945 0.3048)
			(stroke
				(width 0.1)
				(type default)
			)
			(layer "B.Fab")
		)
		(pad "1" smd circle
			(at 0.40005 0)
			(size 0 0)
			(layers "B.Cu" "B.Mask" "B.Paste")
			(net "FRU_E2")
		)
		(pad "2" smd circle
			(at -0.40005 0)
			(size 0 0)
			(layers "B.Cu" "B.Mask" "B.Paste")
			(net "GND")
		)
	)
)
